(kicad_pcb
	(version 20260206)
	(generator "pcbnew")
	(generator_version "10.0")
	(general
		(thickness 1.6)
		(legacy_teardrops no)
	)
	(paper "A4")
	(title_block
		(title "baseboard — 13948-1b.1110WZS1818.brd")
		(comment 1 "Honey Badger (Wiwynn) / footprints 1864-1870 of 2523")
	)
	(layers
		(0 "F.Cu" signal "TOP")
		(4 "In1.Cu" signal "L2GND")
		(6 "In2.Cu" signal "L3")
		(8 "In3.Cu" signal "L4VCC")
		(10 "In4.Cu" signal "L5VCC")
		(12 "In5.Cu" signal "L6")
		(14 "In6.Cu" signal "L7GND")
		(2 "B.Cu" signal "BOTTOM")
		(9 "F.Adhes" user "F.Adhesive")
		(11 "B.Adhes" user "B.Adhesive")
		(13 "F.Paste" user "Package Geometry/Pastemask Top")
		(15 "B.Paste" user "Package Geometry/Pastemask Bottom")
		(5 "F.SilkS" user "Ref Des/Silkscreen Top")
		(7 "B.SilkS" user "Ref Des/Silkscreen Bottom")
		(1 "F.Mask" user "Board Geometry/Soldermask Top")
		(3 "B.Mask" user "Board Geometry/Soldermask Bottom")
		(17 "Dwgs.User" user "User.Drawings")
		(19 "Cmts.User" user "User.Comments")
		(21 "Eco1.User" user "User.Eco1")
		(23 "Eco2.User" user "User.Eco2")
		(25 "Edge.Cuts" user "Board Geometry/Outline")
		(27 "Margin" user)
		(31 "F.CrtYd" user "Package Geometry/Place Bound Top")
		(29 "B.CrtYd" user "Package Geometry/Place Bound Bottom")
		(35 "F.Fab" user "Ref Des/Assembly Top")
		(33 "B.Fab" user "Ref Des/Assembly Bottom")
	)
	(footprint ""
		(layer "B.Cu")
		(at 318.008 -162.814 -90)
		(property "Reference" "R244"
			(at 0 0 90)
			(layer "B.SilkS")
			(hide yes)
			(effects
				(font
					(size 1.27 1.27)
				)
				(justify mirror)
			)
		)
		(property "Value" "0R2J-2-GP"
			(at -0.064008 -3.993896 270)
			(unlocked yes)
			(layer "B.Fab")
			(hide yes)
			(effects
				(font
					(size 1.016 1.016)
					(thickness 0.1524)
				)
				(justify mirror)
			)
		)
		(property "Device Type" "R402H16"
			(at -0.064008 -5.517896 270)
			(unlocked yes)
			(layer "B.Fab")
			(hide yes)
			(effects
				(font
					(size 1.016 1.016)
					(thickness 0.1524)
				)
				(justify mirror)
			)
		)
		(duplicate_pad_numbers_are_jumpers no)
		(fp_line
			(start -0.508 -0.9398)
			(end 0.508 -0.9398)
			(stroke
				(width 0.1524)
				(type default)
			)
			(layer "B.SilkS")
		)
		(fp_line
			(start 0.508 -0.9398)
			(end 0.508 0.9398)
			(stroke
				(width 0.1524)
				(type default)
			)
			(layer "B.SilkS")
		)
		(fp_rect
			(start 0.508 0.9398)
			(end -0.508 -0.9398)
			(stroke
				(width 0)
				(type default)
			)
			(fill no)
			(layer "B.CrtYd")
		)
		(fp_rect
			(start 0.508 0.9398)
			(end -0.508 -0.9398)
			(stroke
				(width 0)
				(type default)
			)
			(fill no)
			(layer "B.Fab")
		)
		(pad "1" smd custom
			(at 0 -0.4445 90)
			(size 0.1397 0.1397)
			(layers "B.Cu" "B.Mask" "B.Paste")
			(net "NIC_SMBUS_SCL")
			(options
				(clearance outline)
				(anchor circle)
			)
			(primitives
				(gr_poly
					(pts
						(arc
							(start -0.1778 0.2794)
							(mid -0.249642 0.249642)
							(end -0.2794 0.1778)
						)
						(arc
							(start -0.2794 -0.1778)
							(mid -0.249642 -0.249642)
							(end -0.1778 -0.2794)
						)
						(arc
							(start 0.1778 -0.2794)
							(mid 0.249642 -0.249642)
							(end 0.2794 -0.1778)
						)
						(arc
							(start 0.2794 0.1778)
							(mid 0.249642 0.249642)
							(end 0.1778 0.2794)
						)
					)
					(width 0)
					(fill yes)
				)
			)
		)
		(pad "2" smd custom
			(at 0 0.4445 90)
			(size 0.1397 0.1397)
			(layers "B.Cu" "B.Mask" "B.Paste")
			(net "BMC0_SMB4_CLK")
			(options
				(clearance outline)
				(anchor circle)
			)
			(primitives
				(gr_poly
					(pts
						(arc
							(start -0.1778 0.2794)
							(mid -0.249642 0.249642)
							(end -0.2794 0.1778)
						)
						(arc
							(start -0.2794 -0.1778)
							(mid -0.249642 -0.249642)
							(end -0.1778 -0.2794)
						)
						(arc
							(start 0.1778 -0.2794)
							(mid 0.249642 -0.249642)
							(end 0.2794 -0.1778)
						)
						(arc
							(start 0.2794 0.1778)
							(mid 0.249642 0.249642)
							(end 0.1778 0.2794)
						)
					)
					(width 0)
					(fill yes)
				)
			)
		)
	)
	(footprint ""
		(layer "B.Cu")
		(at 107.121706 -54.5211 -90)
		(property "Reference" "SC1010"
			(at 0 0 90)
			(layer "B.SilkS")
			(hide yes)
			(effects
				(font
					(size 1.27 1.27)
				)
				(justify mirror)
			)
		)
		(property "Value" "SC1KP50V2KX-1GP"
			(at -1.1811 -2.7051 270)
			(unlocked yes)
			(layer "B.Fab")
			(hide yes)
			(effects
				(font
					(size 1.016 1.016)
					(thickness 0.1524)
				)
				(justify mirror)
			)
		)
		(property "Device Type" "C402H22"
			(at -1.1811 -4.2291 270)
			(unlocked yes)
			(layer "B.Fab")
			(hide yes)
			(effects
				(font
					(size 1.016 1.016)
					(thickness 0.1524)
				)
				(justify mirror)
			)
		)
		(duplicate_pad_numbers_are_jumpers no)
		(fp_rect
			(start 0.4318 0.9525)
			(end -0.4318 -0.9525)
			(stroke
				(width 0)
				(type default)
			)
			(fill no)
			(layer "B.CrtYd")
		)
		(fp_rect
			(start 0.4318 0.9525)
			(end -0.4318 -0.9525)
			(stroke
				(width 0)
				(type default)
			)
			(fill no)
			(layer "B.Fab")
		)
		(pad "1" smd custom
			(at 0 -0.4445 90)
			(size 0.1524 0.1524)
			(layers "B.Cu" "B.Mask" "B.Paste")
			(net "P1V8_C")
			(options
				(clearance outline)
				(anchor circle)
			)
			(primitives
				(gr_poly
					(pts
						(arc
							(start 0.3048 0.2032)
							(mid 0.275042 0.275042)
							(end 0.2032 0.3048)
						)
						(arc
							(start -0.2032 0.3048)
							(mid -0.275042 0.275042)
							(end -0.3048 0.2032)
						)
						(arc
							(start -0.3048 -0.2032)
							(mid -0.275042 -0.275042)
							(end -0.2032 -0.3048)
						)
						(arc
							(start 0.2032 -0.3048)
							(mid 0.275042 -0.275042)
							(end 0.3048 -0.2032)
						)
					)
					(width 0)
					(fill yes)
				)
			)
		)
		(pad "2" smd custom
			(at 0 0.4445 90)
			(size 0.1524 0.1524)
			(layers "B.Cu" "B.Mask" "B.Paste")
			(net "GND")
			(options
				(clearance outline)
				(anchor circle)
			)
			(primitives
				(gr_poly
					(pts
						(arc
							(start 0.3048 0.2032)
							(mid 0.275042 0.275042)
							(end 0.2032 0.3048)
						)
						(arc
							(start -0.2032 0.3048)
							(mid -0.275042 0.275042)
							(end -0.3048 0.2032)
						)
						(arc
							(start -0.3048 -0.2032)
							(mid -0.275042 -0.275042)
							(end -0.2032 -0.3048)
						)
						(arc
							(start 0.2032 -0.3048)
							(mid 0.275042 -0.275042)
							(end 0.3048 -0.2032)
						)
					)
					(width 0)
					(fill yes)
				)
			)
		)
	)
	(footprint ""
		(layer "B.Cu")
		(at 119.16537 -78.4098 90)
		(property "Reference" "SR829"
			(at 0 0 90)
			(layer "B.SilkS")
			(hide yes)
			(effects
				(font
					(size 1.27 1.27)
				)
				(justify mirror)
			)
		)
		(property "Value" "10R2F-L-GP"
			(at -0.064008 -3.993896 90)
			(unlocked yes)
			(layer "B.Fab")
			(hide yes)
			(effects
				(font
					(size 1.016 1.016)
					(thickness 0.1524)
				)
				(justify mirror)
			)
		)
		(property "Device Type" "R402H14"
			(at -0.064008 -5.517896 90)
			(unlocked yes)
			(layer "B.Fab")
			(hide yes)
			(effects
				(font
					(size 1.016 1.016)
					(thickness 0.1524)
				)
				(justify mirror)
			)
		)
		(duplicate_pad_numbers_are_jumpers no)
		(fp_line
			(start 0.508 -0.9398)
			(end 0.508 0.9398)
			(stroke
				(width 0.1524)
				(type default)
			)
			(layer "B.SilkS")
		)
		(fp_line
			(start -0.508 -0.9398)
			(end 0.508 -0.9398)
			(stroke
				(width 0.1524)
				(type default)
			)
			(layer "B.SilkS")
		)
		(fp_rect
			(start 0.508 0.9398)
			(end -0.508 -0.9398)
			(stroke
				(width 0)
				(type default)
			)
			(fill no)
			(layer "B.CrtYd")
		)
		(fp_rect
			(start 0.508 0.9398)
			(end -0.508 -0.9398)
			(stroke
				(width 0)
				(type default)
			)
			(fill no)
			(layer "B.Fab")
		)
		(pad "1" smd custom
			(at 0 -0.4445 270)
			(size 0.1397 0.1397)
			(layers "B.Cu" "B.Mask" "B.Paste")
			(net "P1V8_E")
			(options
				(clearance outline)
				(anchor circle)
			)
			(primitives
				(gr_poly
					(pts
						(arc
							(start -0.1778 0.2794)
							(mid -0.249642 0.249642)
							(end -0.2794 0.1778)
						)
						(arc
							(start -0.2794 -0.1778)
							(mid -0.249642 -0.249642)
							(end -0.1778 -0.2794)
						)
						(arc
							(start 0.1778 -0.2794)
							(mid 0.249642 -0.249642)
							(end 0.2794 -0.1778)
						)
						(arc
							(start 0.2794 0.1778)
							(mid 0.249642 0.249642)
							(end 0.1778 0.2794)
						)
					)
					(width 0)
					(fill yes)
				)
			)
		)
		(pad "2" smd custom
			(at 0 0.4445 270)
			(size 0.1397 0.1397)
			(layers "B.Cu" "B.Mask" "B.Paste")
			(net "XTAL_VDDA18")
			(options
				(clearance outline)
				(anchor circle)
			)
			(primitives
				(gr_poly
					(pts
						(arc
							(start -0.1778 0.2794)
							(mid -0.249642 0.249642)
							(end -0.2794 0.1778)
						)
						(arc
							(start -0.2794 -0.1778)
							(mid -0.249642 -0.249642)
							(end -0.1778 -0.2794)
						)
						(arc
							(start 0.1778 -0.2794)
							(mid 0.249642 -0.249642)
							(end 0.2794 -0.1778)
						)
						(arc
							(start 0.2794 0.1778)
							(mid 0.249642 0.249642)
							(end 0.1778 0.2794)
						)
					)
					(width 0)
					(fill yes)
				)
			)
		)
	)
	(footprint ""
		(layer "B.Cu")
		(at 318.008 -169.418 -90)
		(property "Reference" "R247"
			(at 0 0 90)
			(layer "B.SilkS")
			(hide yes)
			(effects
				(font
					(size 1.27 1.27)
				)
				(justify mirror)
			)
		)
		(property "Value" "0R2J-2-GP"
			(at -0.064008 -3.993896 270)
			(unlocked yes)
			(layer "B.Fab")
			(hide yes)
			(effects
				(font
					(size 1.016 1.016)
					(thickness 0.1524)
				)
				(justify mirror)
			)
		)
		(property "Device Type" "R402H16"
			(at -0.064008 -5.517896 270)
			(unlocked yes)
			(layer "B.Fab")
			(hide yes)
			(effects
				(font
					(size 1.016 1.016)
					(thickness 0.1524)
				)
				(justify mirror)
			)
		)
		(duplicate_pad_numbers_are_jumpers no)
		(fp_line
			(start -0.508 -0.9398)
			(end 0.508 -0.9398)
			(stroke
				(width 0.1524)
				(type default)
			)
			(layer "B.SilkS")
		)
		(fp_line
			(start 0.508 -0.9398)
			(end 0.508 0.9398)
			(stroke
				(width 0.1524)
				(type default)
			)
			(layer "B.SilkS")
		)
		(fp_rect
			(start 0.508 0.9398)
			(end -0.508 -0.9398)
			(stroke
				(width 0)
				(type default)
			)
			(fill no)
			(layer "B.CrtYd")
		)
		(fp_rect
			(start 0.508 0.9398)
			(end -0.508 -0.9398)
			(stroke
				(width 0)
				(type default)
			)
			(fill no)
			(layer "B.Fab")
		)
		(pad "1" smd custom
			(at 0 -0.4445 90)
			(size 0.1397 0.1397)
			(layers "B.Cu" "B.Mask" "B.Paste")
			(net "BMC_I2C_A_SDA")
			(options
				(clearance outline)
				(anchor circle)
			)
			(primitives
				(gr_poly
					(pts
						(arc
							(start -0.1778 0.2794)
							(mid -0.249642 0.249642)
							(end -0.2794 0.1778)
						)
						(arc
							(start -0.2794 -0.1778)
							(mid -0.249642 -0.249642)
							(end -0.1778 -0.2794)
						)
						(arc
							(start 0.1778 -0.2794)
							(mid 0.249642 -0.249642)
							(end 0.2794 -0.1778)
						)
						(arc
							(start 0.2794 0.1778)
							(mid 0.249642 0.249642)
							(end 0.1778 0.2794)
						)
					)
					(width 0)
					(fill yes)
				)
			)
		)
		(pad "2" smd custom
			(at 0 0.4445 90)
			(size 0.1397 0.1397)
			(layers "B.Cu" "B.Mask" "B.Paste")
			(net "BMC0_SMB5_DAT")
			(options
				(clearance outline)
				(anchor circle)
			)
			(primitives
				(gr_poly
					(pts
						(arc
							(start -0.1778 0.2794)
							(mid -0.249642 0.249642)
							(end -0.2794 0.1778)
						)
						(arc
							(start -0.2794 -0.1778)
							(mid -0.249642 -0.249642)
							(end -0.1778 -0.2794)
						)
						(arc
							(start 0.1778 -0.2794)
							(mid 0.249642 -0.249642)
							(end 0.2794 -0.1778)
						)
						(arc
							(start 0.2794 0.1778)
							(mid 0.249642 0.249642)
							(end 0.1778 0.2794)
						)
					)
					(width 0)
					(fill yes)
				)
			)
		)
	)
	(footprint ""
		(layer "B.Cu")
		(at 31.446216 -232.33888)
		(property "Reference" "R508"
			(at 0 0 0)
			(layer "B.SilkS")
			(hide yes)
			(effects
				(font
					(size 1.27 1.27)
				)
				(justify mirror)
			)
		)
		(property "Value" "0R2J-2-GP"
			(at -0.064008 -3.993896 0)
			(unlocked yes)
			(layer "B.Fab")
			(hide yes)
			(effects
				(font
					(size 1.016 1.016)
					(thickness 0.1524)
				)
				(justify mirror)
			)
		)
		(property "Device Type" "R402H16"
			(at -0.064008 -5.517896 0)
			(unlocked yes)
			(layer "B.Fab")
			(hide yes)
			(effects
				(font
					(size 1.016 1.016)
					(thickness 0.1524)
				)
				(justify mirror)
			)
		)
		(duplicate_pad_numbers_are_jumpers no)
		(fp_line
			(start -0.508 -0.9398)
			(end 0.508 -0.9398)
			(stroke
				(width 0.1524)
				(type default)
			)
			(layer "B.SilkS")
		)
		(fp_line
			(start 0.508 -0.9398)
			(end 0.508 0.9398)
			(stroke
				(width 0.1524)
				(type default)
			)
			(layer "B.SilkS")
		)
		(fp_rect
			(start 0.508 0.9398)
			(end -0.508 -0.9398)
			(stroke
				(width 0)
				(type default)
			)
			(fill no)
			(layer "B.CrtYd")
		)
		(fp_rect
			(start 0.508 0.9398)
			(end -0.508 -0.9398)
			(stroke
				(width 0)
				(type default)
			)
			(fill no)
			(layer "B.Fab")
		)
		(pad "1" smd custom
			(at 0 -0.4445 180)
			(size 0.1397 0.1397)
			(layers "B.Cu" "B.Mask" "B.Paste")
			(net "SAS_HDD_PWR6_PCIE")
			(options
				(clearance outline)
				(anchor circle)
			)
			(primitives
				(gr_poly
					(pts
						(arc
							(start -0.1778 0.2794)
							(mid -0.249642 0.249642)
							(end -0.2794 0.1778)
						)
						(arc
							(start -0.2794 -0.1778)
							(mid -0.249642 -0.249642)
							(end -0.1778 -0.2794)
						)
						(arc
							(start 0.1778 -0.2794)
							(mid 0.249642 -0.249642)
							(end 0.2794 -0.1778)
						)
						(arc
							(start 0.2794 0.1778)
							(mid 0.249642 0.249642)
							(end 0.1778 0.2794)
						)
					)
					(width 0)
					(fill yes)
				)
			)
		)
		(pad "2" smd custom
			(at 0 0.4445 180)
			(size 0.1397 0.1397)
			(layers "B.Cu" "B.Mask" "B.Paste")
			(net "SAS_HDD_PWR6")
			(options
				(clearance outline)
				(anchor circle)
			)
			(primitives
				(gr_poly
					(pts
						(arc
							(start -0.1778 0.2794)
							(mid -0.249642 0.249642)
							(end -0.2794 0.1778)
						)
						(arc
							(start -0.2794 -0.1778)
							(mid -0.249642 -0.249642)
							(end -0.1778 -0.2794)
						)
						(arc
							(start 0.1778 -0.2794)
							(mid 0.249642 -0.249642)
							(end 0.2794 -0.1778)
						)
						(arc
							(start 0.2794 0.1778)
							(mid 0.249642 0.249642)
							(end 0.1778 0.2794)
						)
					)
					(width 0)
					(fill yes)
				)
			)
		)
	)
	(footprint ""
		(layer "B.Cu")
		(at 96.901 -228.981 -90)
		(property "Reference" "R629"
			(at 0 0 90)
			(layer "B.SilkS")
			(hide yes)
			(effects
				(font
					(size 1.27 1.27)
				)
				(justify mirror)
			)
		)
		(property "Value" "0R2J-2-GP"
			(at -0.064008 -3.993896 270)
			(unlocked yes)
			(layer "B.Fab")
			(hide yes)
			(effects
				(font
					(size 1.016 1.016)
					(thickness 0.1524)
				)
				(justify mirror)
			)
		)
		(property "Device Type" "R402H16"
			(at -0.064008 -5.517896 270)
			(unlocked yes)
			(layer "B.Fab")
			(hide yes)
			(effects
				(font
					(size 1.016 1.016)
					(thickness 0.1524)
				)
				(justify mirror)
			)
		)
		(duplicate_pad_numbers_are_jumpers no)
		(fp_line
			(start -0.508 -0.9398)
			(end 0.508 -0.9398)
			(stroke
				(width 0.1524)
				(type default)
			)
			(layer "B.SilkS")
		)
		(fp_line
			(start 0.508 -0.9398)
			(end 0.508 0.9398)
			(stroke
				(width 0.1524)
				(type default)
			)
			(layer "B.SilkS")
		)
		(fp_rect
			(start 0.508 0.9398)
			(end -0.508 -0.9398)
			(stroke
				(width 0)
				(type default)
			)
			(fill no)
			(layer "B.CrtYd")
		)
		(fp_rect
			(start 0.508 0.9398)
			(end -0.508 -0.9398)
			(stroke
				(width 0)
				(type default)
			)
			(fill no)
			(layer "B.Fab")
		)
		(pad "1" smd custom
			(at 0 -0.4445 90)
			(size 0.1397 0.1397)
			(layers "B.Cu" "B.Mask" "B.Paste")
			(net "SAS_FAULT_LED11")
			(options
				(clearance outline)
				(anchor circle)
			)
			(primitives
				(gr_poly
					(pts
						(arc
							(start -0.1778 0.2794)
							(mid -0.249642 0.249642)
							(end -0.2794 0.1778)
						)
						(arc
							(start -0.2794 -0.1778)
							(mid -0.249642 -0.249642)
							(end -0.1778 -0.2794)
						)
						(arc
							(start 0.1778 -0.2794)
							(mid 0.249642 -0.249642)
							(end 0.2794 -0.1778)
						)
						(arc
							(start 0.2794 0.1778)
							(mid 0.249642 0.249642)
							(end 0.1778 0.2794)
						)
					)
					(width 0)
					(fill yes)
				)
			)
		)
		(pad "2" smd custom
			(at 0 0.4445 90)
			(size 0.1397 0.1397)
			(layers "B.Cu" "B.Mask" "B.Paste")
			(net "SAS_HDD_LED_11")
			(options
				(clearance outline)
				(anchor circle)
			)
			(primitives
				(gr_poly
					(pts
						(arc
							(start -0.1778 0.2794)
							(mid -0.249642 0.249642)
							(end -0.2794 0.1778)
						)
						(arc
							(start -0.2794 -0.1778)
							(mid -0.249642 -0.249642)
							(end -0.1778 -0.2794)
						)
						(arc
							(start 0.1778 -0.2794)
							(mid 0.249642 -0.249642)
							(end 0.2794 -0.1778)
						)
						(arc
							(start 0.2794 0.1778)
							(mid 0.249642 0.249642)
							(end 0.1778 0.2794)
						)
					)
					(width 0)
					(fill yes)
				)
			)
		)
	)
	(footprint ""
		(layer "B.Cu")
		(at 180.013864 -32.965136 90)
		(property "Reference" "C220"
			(at 0 0 90)
			(layer "B.SilkS")
			(hide yes)
			(effects
				(font
					(size 1.27 1.27)
				)
				(justify mirror)
			)
		)
		(property "Value" "SC1KP50V2KX-1GP"
			(at -1.1811 -2.7051 90)
			(unlocked yes)
			(layer "B.Fab")
			(hide yes)
			(effects
				(font
					(size 1.016 1.016)
					(thickness 0.1524)
				)
				(justify mirror)
			)
		)
		(property "Device Type" "C402H22"
			(at -1.1811 -4.2291 90)
			(unlocked yes)
			(layer "B.Fab")
			(hide yes)
			(effects
				(font
					(size 1.016 1.016)
					(thickness 0.1524)
				)
				(justify mirror)
			)
		)
		(duplicate_pad_numbers_are_jumpers no)
		(fp_rect
			(start 0.4318 0.9525)
			(end -0.4318 -0.9525)
			(stroke
				(width 0)
				(type default)
			)
			(fill no)
			(layer "B.CrtYd")
		)
		(fp_rect
			(start 0.4318 0.9525)
			(end -0.4318 -0.9525)
			(stroke
				(width 0)
				(type default)
			)
			(fill no)
			(layer "B.Fab")
		)
		(pad "1" smd custom
			(at 0 -0.4445 270)
			(size 0.1524 0.1524)
			(layers "B.Cu" "B.Mask" "B.Paste")
			(net "P3V3_STBY")
			(options
				(clearance outline)
				(anchor circle)
			)
			(primitives
				(gr_poly
					(pts
						(arc
							(start 0.3048 0.2032)
							(mid 0.275042 0.275042)
							(end 0.2032 0.3048)
						)
						(arc
							(start -0.2032 0.3048)
							(mid -0.275042 0.275042)
							(end -0.3048 0.2032)
						)
						(arc
							(start -0.3048 -0.2032)
							(mid -0.275042 -0.275042)
							(end -0.2032 -0.3048)
						)
						(arc
							(start 0.2032 -0.3048)
							(mid 0.275042 -0.275042)
							(end 0.3048 -0.2032)
						)
					)
					(width 0)
					(fill yes)
				)
			)
		)
		(pad "2" smd custom
			(at 0 0.4445 270)
			(size 0.1524 0.1524)
			(layers "B.Cu" "B.Mask" "B.Paste")
			(net "GND")
			(options
				(clearance outline)
				(anchor circle)
			)
			(primitives
				(gr_poly
					(pts
						(arc
							(start 0.3048 0.2032)
							(mid 0.275042 0.275042)
							(end 0.2032 0.3048)
						)
						(arc
							(start -0.2032 0.3048)
							(mid -0.275042 0.275042)
							(end -0.3048 0.2032)
						)
						(arc
							(start -0.3048 -0.2032)
							(mid -0.275042 -0.275042)
							(end -0.2032 -0.3048)
						)
						(arc
							(start 0.2032 -0.3048)
							(mid 0.275042 -0.275042)
							(end 0.3048 -0.2032)
						)
					)
					(width 0)
					(fill yes)
				)
			)
		)
	)
)
